(kicad_pcb
	(version 20260206)
	(generator "pcbnew")
	(generator_version "10.0")
	(general
		(thickness 1.6)
		(legacy_teardrops no)
	)
	(paper "A4")
	(title_block
		(title "Wiwynn_Tioga_Pass_MB.brd")
		(comment 1 "Tioga Pass / footprints 1433-1439 of 4770")
	)
	(layers
		(0 "F.Cu" signal "TOP")
		(4 "In1.Cu" signal "L2GND")
		(6 "In2.Cu" signal "L3")
		(8 "In3.Cu" signal "L4GND")
		(10 "In4.Cu" signal "L5")
		(12 "In5.Cu" signal "L6GND")
		(14 "In6.Cu" signal "L7VCC")
		(16 "In7.Cu" signal "L8VCC")
		(18 "In8.Cu" signal "L9GND")
		(20 "In9.Cu" signal "L10")
		(22 "In10.Cu" signal "L11GND")
		(24 "In11.Cu" signal "L12")
		(26 "In12.Cu" signal "L13GND")
		(2 "B.Cu" signal "BOTTOM")
		(9 "F.Adhes" user "F.Adhesive")
		(11 "B.Adhes" user "B.Adhesive")
		(13 "F.Paste" user "Package Geometry/Pastemask Top")
		(15 "B.Paste" user "Package Geometry/Pastemask Bottom")
		(5 "F.SilkS" user "Ref Des/Silkscreen Top")
		(7 "B.SilkS" user "Ref Des/Silkscreen Bottom")
		(1 "F.Mask" user "Board Geometry/Soldermask Top")
		(3 "B.Mask" user "Board Geometry/Soldermask Bottom")
		(17 "Dwgs.User" user "User.Drawings")
		(19 "Cmts.User" user "User.Comments")
		(21 "Eco1.User" user "User.Eco1")
		(23 "Eco2.User" user "User.Eco2")
		(25 "Edge.Cuts" user "Board Geometry/Outline")
		(27 "Margin" user)
		(31 "F.CrtYd" user "Package Geometry/Place Bound Top")
		(29 "B.CrtYd" user "Package Geometry/Place Bound Bottom")
		(35 "F.Fab" user "Ref Des/Assembly Top")
		(33 "B.Fab" user "Ref Des/Assembly Bottom")
	)
	(footprint ""
		(layer "F.Cu")
		(at 408.7495 -110.617 -90)
		(property "Reference" "R8C4"
			(at 0 0 270)
			(layer "F.SilkS")
			(hide yes)
			(effects
				(font
					(size 1.27 1.27)
				)
			)
		)
		(property "Value" ""
			(at 0 0 270)
			(layer "F.Fab")
			(effects
				(font
					(size 1.27 1.27)
				)
			)
		)
		(duplicate_pad_numbers_are_jumpers no)
		(fp_poly
			(pts
				(xy -0.2794 -0.1016) (xy 0.2794 -0.1016) (xy 0.2794 0.9906) (xy -0.2794 0.9906)
			)
			(stroke
				(width 0)
				(type default)
			)
			(fill no)
			(layer "F.CrtYd")
		)
		(fp_line
			(start -0.2794 0.9906)
			(end 0.2794 0.9906)
			(stroke
				(width 0.1)
				(type default)
			)
			(layer "F.Fab")
		)
		(fp_line
			(start 0.2794 0.9906)
			(end 0.2794 -0.1016)
			(stroke
				(width 0.1)
				(type default)
			)
			(layer "F.Fab")
		)
		(fp_line
			(start -0.2794 -0.1016)
			(end -0.2794 0.9906)
			(stroke
				(width 0.1)
				(type default)
			)
			(layer "F.Fab")
		)
		(fp_line
			(start 0.2794 -0.1016)
			(end -0.2794 -0.1016)
			(stroke
				(width 0.1)
				(type default)
			)
			(layer "F.Fab")
		)
		(pad "1" smd rect
			(at 0 0 270)
			(size 0.508 0.508)
			(layers "F.Cu" "F.Mask" "F.Paste")
			(net "P3V3_STBY")
		)
		(pad "2" smd rect
			(at 0 0.889 270)
			(size 0.508 0.508)
			(layers "F.Cu" "F.Mask" "F.Paste")
			(net "IRQ_BMC_PCH_SMI_LPC_N")
		)
		(zone
			(layer "F.Cu")
			(hatch none 0.5)
			(connect_pads
				(clearance 0)
			)
			(min_thickness 0.25)
			(keepout
				(tracks not_allowed)
				(vias allowed)
				(pads allowed)
				(copperpour not_allowed)
				(footprints allowed)
			)
			(placement
				(enabled no)
				(sheetname "")
			)
			(fill
				(thermal_gap 0.5)
				(thermal_bridge_width 0.5)
				(island_removal_mode 0)
			)
			(polygon
				(pts
					(xy 408.1145 -110.871) (xy 408.1145 -110.363) (xy 408.4955 -110.363) (xy 408.4955 -110.871)
				)
			)
		)
		(zone
			(layer "F.Cu")
			(hatch none 0.5)
			(connect_pads
				(clearance 0)
			)
			(min_thickness 0.25)
			(keepout
				(tracks allowed)
				(vias not_allowed)
				(pads allowed)
				(copperpour not_allowed)
				(footprints allowed)
			)
			(placement
				(enabled no)
				(sheetname "")
			)
			(fill
				(thermal_gap 0.5)
				(thermal_bridge_width 0.5)
				(island_removal_mode 0)
			)
			(polygon
				(pts
					(xy 408.4955 -110.871) (xy 408.4955 -110.363) (xy 408.1145 -110.363) (xy 408.1145 -110.871)
				)
			)
		)
	)
	(footprint ""
		(layer "F.Cu")
		(at 142.810484 12.014454 -90)
		(property "Reference" "T1P12"
			(at 0 0 270)
			(layer "F.SilkS")
			(hide yes)
			(effects
				(font
					(size 1.27 1.27)
				)
			)
		)
		(property "Value" "*"
			(at -3.302 1.12395 270)
			(unlocked yes)
			(layer "F.Fab")
			(hide yes)
			(effects
				(font
					(size 0.889 0.889)
					(thickness 0.1524)
				)
			)
		)
		(property "Device Type" "TPAD-DIFF-4P-GP_DISCRET-GB3-TPA"
			(at -3.302 -0.40005 270)
			(unlocked yes)
			(layer "F.Fab")
			(hide yes)
			(effects
				(font
					(size 0.889 0.889)
					(thickness 0.1524)
				)
			)
		)
		(duplicate_pad_numbers_are_jumpers no)
		(fp_line
			(start -2.286 2.286)
			(end 2.286 2.286)
			(stroke
				(width 0.1524)
				(type default)
			)
			(layer "F.SilkS")
		)
		(fp_line
			(start 2.286 2.286)
			(end 2.286 -2.286)
			(stroke
				(width 0.1524)
				(type default)
			)
			(layer "F.SilkS")
		)
		(fp_line
			(start -2.286 -2.286)
			(end -2.286 2.286)
			(stroke
				(width 0.1524)
				(type default)
			)
			(layer "F.SilkS")
		)
		(fp_line
			(start 2.286 -2.286)
			(end -2.286 -2.286)
			(stroke
				(width 0.1524)
				(type default)
			)
			(layer "F.SilkS")
		)
		(fp_line
			(start -2.413 -2.413)
			(end -2.413 -1.143)
			(stroke
				(width 0.4064)
				(type default)
			)
			(layer "F.SilkS")
		)
		(fp_line
			(start -1.143 -2.413)
			(end -2.413 -2.413)
			(stroke
				(width 0.4064)
				(type default)
			)
			(layer "F.SilkS")
		)
		(fp_rect
			(start -2.54 2.54)
			(end 2.54 -2.54)
			(stroke
				(width 0)
				(type default)
			)
			(fill no)
			(layer "F.CrtYd")
		)
		(fp_rect
			(start -2.54 2.54)
			(end 2.54 -2.54)
			(stroke
				(width 0)
				(type default)
			)
			(fill no)
			(layer "F.Fab")
		)
		(pad "1" thru_hole circle
			(at -1.27 -1.27 270)
			(size 1.524 1.524)
			(drill 0.9144)
			(layers "*.Cu" "*.Mask")
			(remove_unused_layers no)
			(net "L14_73OHM_6INCH_DP")
			(clearance -0.0508)
			(thermal_gap 0.127)
			(padstack
				(mode front_inner_back)
				(layer "Inner"
					(shape circle)
					(size 1.1684 1.1684)
					(clearance 0.127)
				)
				(layer "B.Cu"
					(shape circle)
					(size 1.524 1.524)
					(clearance -0.0508)
				)
			)
		)
		(pad "2" thru_hole circle
			(at 1.27 -1.27 270)
			(size 1.524 1.524)
			(drill 0.9144)
			(layers "*.Cu" "*.Mask")
			(remove_unused_layers no)
			(net "L14_73OHM_6INCH_DN")
			(clearance -0.0508)
			(thermal_gap 0.127)
			(padstack
				(mode front_inner_back)
				(layer "Inner"
					(shape circle)
					(size 1.1684 1.1684)
					(clearance 0.127)
				)
				(layer "B.Cu"
					(shape circle)
					(size 1.524 1.524)
					(clearance -0.0508)
				)
			)
		)
		(pad "GND1" thru_hole rect
			(at -1.27 1.27 270)
			(size 1.524 1.524)
			(drill 0.9144)
			(layers "*.Cu" "*.Mask")
			(remove_unused_layers no)
			(net "GND")
			(clearance -0.0508)
			(thermal_gap 0.127)
			(padstack
				(mode front_inner_back)
				(layer "Inner"
					(shape circle)
					(size 1.1684 1.1684)
					(clearance 0.127)
				)
				(layer "B.Cu"
					(shape rect)
					(size 1.524 1.524)
					(clearance -0.0508)
				)
			)
		)
		(pad "GND2" thru_hole rect
			(at 1.27 1.27 270)
			(size 1.524 1.524)
			(drill 0.9144)
			(layers "*.Cu" "*.Mask")
			(remove_unused_layers no)
			(net "GND")
			(clearance -0.0508)
			(thermal_gap 0.127)
			(padstack
				(mode front_inner_back)
				(layer "Inner"
					(shape circle)
					(size 1.1684 1.1684)
					(clearance 0.127)
				)
				(layer "B.Cu"
					(shape rect)
					(size 1.524 1.524)
					(clearance -0.0508)
				)
			)
		)
	)
	(footprint ""
		(layer "F.Cu")
		(at 27.888946 -75.024742 90)
		(property "Reference" "C1D20"
			(at 0 0 90)
			(layer "F.SilkS")
			(hide yes)
			(effects
				(font
					(size 1.27 1.27)
				)
			)
		)
		(property "Value" ""
			(at 0 0 90)
			(layer "F.Fab")
			(effects
				(font
					(size 1.27 1.27)
				)
			)
		)
		(duplicate_pad_numbers_are_jumpers no)
		(fp_rect
			(start -0.3048 0.9906)
			(end 0.3048 -0.1016)
			(stroke
				(width 0)
				(type default)
			)
			(fill no)
			(layer "F.CrtYd")
		)
		(fp_line
			(start 0.3048 -0.1016)
			(end -0.3048 -0.1016)
			(stroke
				(width 0.1)
				(type default)
			)
			(layer "F.Fab")
		)
		(fp_line
			(start -0.3048 -0.1016)
			(end -0.3048 0.9906)
			(stroke
				(width 0.1)
				(type default)
			)
			(layer "F.Fab")
		)
		(fp_line
			(start 0.3048 0.9906)
			(end 0.3048 -0.1016)
			(stroke
				(width 0.1)
				(type default)
			)
			(layer "F.Fab")
		)
		(fp_line
			(start -0.3048 0.9906)
			(end 0.3048 0.9906)
			(stroke
				(width 0.1)
				(type default)
			)
			(layer "F.Fab")
		)
		(pad "1" smd rect
			(at 0 0 90)
			(size 0.508 0.508)
			(layers "F.Cu" "F.Mask" "F.Paste")
			(net "VR_PVCCIN_CPU1_PH3_BOOT")
		)
		(pad "2" smd rect
			(at 0 0.889 90)
			(size 0.508 0.508)
			(layers "F.Cu" "F.Mask" "F.Paste")
			(net "VR_PVCCIN_CPU1_PH3_PHASE")
		)
		(zone
			(layer "F.Cu")
			(hatch none 0.5)
			(connect_pads
				(clearance 0)
			)
			(min_thickness 0.25)
			(keepout
				(tracks allowed)
				(vias not_allowed)
				(pads allowed)
				(copperpour not_allowed)
				(footprints allowed)
			)
			(placement
				(enabled no)
				(sheetname "")
			)
			(fill
				(thermal_gap 0.5)
				(thermal_bridge_width 0.5)
				(island_removal_mode 0)
			)
			(polygon
				(pts
					(xy 28.523946 -74.770742) (xy 28.523946 -75.278742) (xy 28.142946 -75.278742) (xy 28.142946 -74.770742)
				)
			)
		)
		(zone
			(layer "F.Cu")
			(hatch none 0.5)
			(connect_pads
				(clearance 0)
			)
			(min_thickness 0.25)
			(keepout
				(tracks not_allowed)
				(vias allowed)
				(pads allowed)
				(copperpour not_allowed)
				(footprints allowed)
			)
			(placement
				(enabled no)
				(sheetname "")
			)
			(fill
				(thermal_gap 0.5)
				(thermal_bridge_width 0.5)
				(island_removal_mode 0)
			)
			(polygon
				(pts
					(xy 28.523946 -74.770742) (xy 28.523946 -75.278742) (xy 28.142946 -75.278742) (xy 28.142946 -74.770742)
				)
			)
		)
	)
	(footprint ""
		(layer "F.Cu")
		(at 473.075 -38.1 180)
		(property "Reference" "C9F10"
			(at 0 0 180)
			(layer "F.SilkS")
			(hide yes)
			(effects
				(font
					(size 1.27 1.27)
				)
			)
		)
		(property "Value" ""
			(at 0 0 180)
			(layer "F.Fab")
			(effects
				(font
					(size 1.27 1.27)
				)
			)
		)
		(duplicate_pad_numbers_are_jumpers no)
		(fp_poly
			(pts
				(xy 0.3048 -0.1016) (xy 0.3048 0.9906) (xy -0.3048 0.9906) (xy -0.3048 -0.1016)
			)
			(stroke
				(width 0)
				(type default)
			)
			(fill no)
			(layer "F.CrtYd")
		)
		(fp_line
			(start 0.3048 0.9906)
			(end 0.3048 -0.1016)
			(stroke
				(width 0.1)
				(type default)
			)
			(layer "F.Fab")
		)
		(fp_line
			(start 0.3048 -0.1016)
			(end -0.3048 -0.1016)
			(stroke
				(width 0.1)
				(type default)
			)
			(layer "F.Fab")
		)
		(fp_line
			(start -0.3048 0.9906)
			(end 0.3048 0.9906)
			(stroke
				(width 0.1)
				(type default)
			)
			(layer "F.Fab")
		)
		(fp_line
			(start -0.3048 -0.1016)
			(end -0.3048 0.9906)
			(stroke
				(width 0.1)
				(type default)
			)
			(layer "F.Fab")
		)
		(pad "1" smd rect
			(at 0 0 180)
			(size 0.508 0.508)
			(layers "F.Cu" "F.Mask" "F.Paste")
			(net "PWRGD_P1V2_BMC_STBY_R")
		)
		(pad "2" smd rect
			(at 0 0.889 180)
			(size 0.508 0.508)
			(layers "F.Cu" "F.Mask" "F.Paste")
			(net "GND")
		)
		(zone
			(layer "F.Cu")
			(hatch none 0.5)
			(connect_pads
				(clearance 0)
			)
			(min_thickness 0.25)
			(keepout
				(tracks not_allowed)
				(vias allowed)
				(pads allowed)
				(copperpour not_allowed)
				(footprints allowed)
			)
			(placement
				(enabled no)
				(sheetname "")
			)
			(fill
				(thermal_gap 0.5)
				(thermal_bridge_width 0.5)
				(island_removal_mode 0)
			)
			(polygon
				(pts
					(xy 473.329 -38.735) (xy 472.821 -38.735) (xy 472.821 -38.354) (xy 473.329 -38.354)
				)
			)
		)
		(zone
			(layer "F.Cu")
			(hatch none 0.5)
			(connect_pads
				(clearance 0)
			)
			(min_thickness 0.25)
			(keepout
				(tracks allowed)
				(vias not_allowed)
				(pads allowed)
				(copperpour not_allowed)
				(footprints allowed)
			)
			(placement
				(enabled no)
				(sheetname "")
			)
			(fill
				(thermal_gap 0.5)
				(thermal_bridge_width 0.5)
				(island_removal_mode 0)
			)
			(polygon
				(pts
					(xy 473.329 -38.354) (xy 472.821 -38.354) (xy 472.821 -38.735) (xy 473.329 -38.735)
				)
			)
		)
	)
	(footprint ""
		(layer "F.Cu")
		(at 343.281 -20.447)
		(property "Reference" "R7F22"
			(at 0 0 0)
			(layer "F.SilkS")
			(hide yes)
			(effects
				(font
					(size 1.27 1.27)
				)
			)
		)
		(property "Value" ""
			(at 0 0 0)
			(layer "F.Fab")
			(effects
				(font
					(size 1.27 1.27)
				)
			)
		)
		(duplicate_pad_numbers_are_jumpers no)
		(fp_rect
			(start -0.2794 0.9906)
			(end 0.2794 -0.1016)
			(stroke
				(width 0)
				(type default)
			)
			(fill no)
			(layer "F.CrtYd")
		)
		(fp_line
			(start -0.2794 -0.1016)
			(end -0.2794 0.9906)
			(stroke
				(width 0.1)
				(type default)
			)
			(layer "F.Fab")
		)
		(fp_line
			(start -0.2794 0.9906)
			(end 0.2794 0.9906)
			(stroke
				(width 0.1)
				(type default)
			)
			(layer "F.Fab")
		)
		(fp_line
			(start 0.2794 -0.1016)
			(end -0.2794 -0.1016)
			(stroke
				(width 0.1)
				(type default)
			)
			(layer "F.Fab")
		)
		(fp_line
			(start 0.2794 0.9906)
			(end 0.2794 -0.1016)
			(stroke
				(width 0.1)
				(type default)
			)
			(layer "F.Fab")
		)
		(pad "1" smd rect
			(at 0 0)
			(size 0.508 0.508)
			(layers "F.Cu" "F.Mask" "F.Paste")
			(net "P3V3_STBY")
		)
		(pad "2" smd rect
			(at 0 0.889)
			(size 0.508 0.508)
			(layers "F.Cu" "F.Mask" "F.Paste")
			(net "PWRGD_PVDDQ_ABC_R")
		)
		(zone
			(layer "F.Cu")
			(hatch none 0.5)
			(connect_pads
				(clearance 0)
			)
			(min_thickness 0.25)
			(keepout
				(tracks not_allowed)
				(vias allowed)
				(pads allowed)
				(copperpour not_allowed)
				(footprints allowed)
			)
			(placement
				(enabled no)
				(sheetname "")
			)
			(fill
				(thermal_gap 0.5)
				(thermal_bridge_width 0.5)
				(island_removal_mode 0)
			)
			(polygon
				(pts
					(xy 343.027 -19.812) (xy 343.535 -19.812) (xy 343.535 -20.193) (xy 343.027 -20.193)
				)
			)
		)
		(zone
			(layer "F.Cu")
			(hatch none 0.5)
			(connect_pads
				(clearance 0)
			)
			(min_thickness 0.25)
			(keepout
				(tracks allowed)
				(vias not_allowed)
				(pads allowed)
				(copperpour not_allowed)
				(footprints allowed)
			)
			(placement
				(enabled no)
				(sheetname "")
			)
			(fill
				(thermal_gap 0.5)
				(thermal_bridge_width 0.5)
				(island_removal_mode 0)
			)
			(polygon
				(pts
					(xy 343.027 -19.812) (xy 343.535 -19.812) (xy 343.535 -20.193) (xy 343.027 -20.193)
				)
			)
		)
	)
	(footprint ""
		(layer "F.Cu")
		(at 24.257 10.7315 -90)
		(property "Reference" "T1P28"
			(at 0 0 270)
			(layer "F.SilkS")
			(hide yes)
			(effects
				(font
					(size 1.27 1.27)
				)
			)
		)
		(property "Value" "*"
			(at 0 -3.44805 270)
			(unlocked yes)
			(layer "F.Fab")
			(hide yes)
			(effects
				(font
					(size 0.889 0.889)
					(thickness 0.1524)
				)
			)
		)
		(property "Device Type" "TPAD-SE-2P-GP_DISCRET-GA1-TPADA"
			(at 0 -4.97205 270)
			(unlocked yes)
			(layer "F.Fab")
			(hide yes)
			(effects
				(font
					(size 0.889 0.889)
					(thickness 0.1524)
				)
			)
		)
		(duplicate_pad_numbers_are_jumpers no)
		(fp_line
			(start -1.016 2.286)
			(end -1.016 -2.286)
			(stroke
				(width 0.1524)
				(type default)
			)
			(layer "F.SilkS")
		)
		(fp_line
			(start 1.016 2.286)
			(end -1.016 2.286)
			(stroke
				(width 0.1524)
				(type default)
			)
			(layer "F.SilkS")
		)
		(fp_line
			(start -1.016 -2.286)
			(end 1.016 -2.286)
			(stroke
				(width 0.1524)
				(type default)
			)
			(layer "F.SilkS")
		)
		(fp_line
			(start 1.016 -2.286)
			(end 1.016 2.286)
			(stroke
				(width 0.1524)
				(type default)
			)
			(layer "F.SilkS")
		)
		(fp_rect
			(start -1.27 2.54)
			(end 1.27 -2.54)
			(stroke
				(width 0)
				(type default)
			)
			(fill no)
			(layer "F.CrtYd")
		)
		(fp_rect
			(start -1.27 2.54)
			(end 1.27 -2.54)
			(stroke
				(width 0)
				(type default)
			)
			(fill no)
			(layer "F.Fab")
		)
		(pad "1" thru_hole circle
			(at 0 -1.27 270)
			(size 1.524 1.524)
			(drill 0.9144)
			(layers "*.Cu" "*.Mask")
			(remove_unused_layers no)
			(net "L10_40OHM_6INCH")
			(clearance -0.0508)
			(thermal_gap 0.127)
			(padstack
				(mode front_inner_back)
				(layer "Inner"
					(shape circle)
					(size 1.1684 1.1684)
					(clearance 0.127)
				)
				(layer "B.Cu"
					(shape circle)
					(size 1.524 1.524)
					(clearance -0.0508)
				)
			)
		)
		(pad "GND1" thru_hole rect
			(at 0 1.27 270)
			(size 1.524 1.524)
			(drill 0.9144)
			(layers "*.Cu" "*.Mask")
			(remove_unused_layers no)
			(net "GND")
			(clearance -0.0508)
			(thermal_gap 0.127)
			(padstack
				(mode front_inner_back)
				(layer "Inner"
					(shape circle)
					(size 1.1684 1.1684)
					(clearance 0.127)
				)
				(layer "B.Cu"
					(shape rect)
					(size 1.524 1.524)
					(clearance -0.0508)
				)
			)
		)
	)
	(footprint ""
		(layer "F.Cu")
		(at 426.4533 -124.9172 -90)
		(property "Reference" "R8B16"
			(at 0 0 270)
			(layer "F.SilkS")
			(hide yes)
			(effects
				(font
					(size 1.27 1.27)
				)
			)
		)
		(property "Value" ""
			(at 0 0 270)
			(layer "F.Fab")
			(effects
				(font
					(size 1.27 1.27)
				)
			)
		)
		(duplicate_pad_numbers_are_jumpers no)
		(fp_poly
			(pts
				(xy -0.2794 -0.1016) (xy 0.2794 -0.1016) (xy 0.2794 0.9906) (xy -0.2794 0.9906)
			)
			(stroke
				(width 0)
				(type default)
			)
			(fill no)
			(layer "F.CrtYd")
		)
		(fp_line
			(start -0.2794 0.9906)
			(end 0.2794 0.9906)
			(stroke
				(width 0.1)
				(type default)
			)
			(layer "F.Fab")
		)
		(fp_line
			(start 0.2794 0.9906)
			(end 0.2794 -0.1016)
			(stroke
				(width 0.1)
				(type default)
			)
			(layer "F.Fab")
		)
		(fp_line
			(start -0.2794 -0.1016)
			(end -0.2794 0.9906)
			(stroke
				(width 0.1)
				(type default)
			)
			(layer "F.Fab")
		)
		(fp_line
			(start 0.2794 -0.1016)
			(end -0.2794 -0.1016)
			(stroke
				(width 0.1)
				(type default)
			)
			(layer "F.Fab")
		)
		(pad "1" smd rect
			(at 0 0 270)
			(size 0.508 0.508)
			(layers "F.Cu" "F.Mask" "F.Paste")
			(net "PVPP_ABC")
		)
		(pad "2" smd rect
			(at 0 0.889 270)
			(size 0.508 0.508)
			(layers "F.Cu" "F.Mask" "F.Paste")
			(net "RST_HFI1_CPU0_LVT2_N")
		)
		(zone
			(layer "F.Cu")
			(hatch none 0.5)
			(connect_pads
				(clearance 0)
			)
			(min_thickness 0.25)
			(keepout
				(tracks not_allowed)
				(vias allowed)
				(pads allowed)
				(copperpour not_allowed)
				(footprints allowed)
			)
			(placement
				(enabled no)
				(sheetname "")
			)
			(fill
				(thermal_gap 0.5)
				(thermal_bridge_width 0.5)
				(island_removal_mode 0)
			)
			(polygon
				(pts
					(xy 425.8183 -125.1712) (xy 425.8183 -124.6632) (xy 426.1993 -124.6632) (xy 426.1993 -125.1712)
				)
			)
		)
		(zone
			(layer "F.Cu")
			(hatch none 0.5)
			(connect_pads
				(clearance 0)
			)
			(min_thickness 0.25)
			(keepout
				(tracks allowed)
				(vias not_allowed)
				(pads allowed)
				(copperpour not_allowed)
				(footprints allowed)
			)
			(placement
				(enabled no)
				(sheetname "")
			)
			(fill
				(thermal_gap 0.5)
				(thermal_bridge_width 0.5)
				(island_removal_mode 0)
			)
			(polygon
				(pts
					(xy 426.1993 -125.1712) (xy 426.1993 -124.6632) (xy 425.8183 -124.6632) (xy 425.8183 -125.1712)
				)
			)
		)
	)
)
